# S9S_MB_2U (Grand Teton) — schematic netlist excerpt (pin names and nets, part order shuffled) for the footprints in the layout excerpt that follows; sources: Cadence DE-HDL packaged netlist, KiCad conversion of 03242023_DA0F0TMBIJ0_F0T_Motherboard_J_brd_V01_OCP.brd

J28  SCONN288_ADR50017P087CC  SCONN288_ADR50017-P087CC IO  pkg DDR288S_1-1VXB  page 109
  VIN_BULK0  = P12V_S3_AUX_CPU1_NVDIMM
  RFU0  = TP_CHF_CPU1_DIMM2_FRU_0
  VIN_MGMT  = P3V3_AUX
  HSCL  = I3C_SPD_DDREFGH_CPU1_LVC1_SCL_3
  HSDA  = I3C_SPD_DDREFGH_CPU1_LVC1_SDA
  VSS0  = GND
  DQ0_A  = M_F_CPU1_SA_DQ<0>
  VSS1  = GND
  DQ1_A  = M_F_CPU1_SA_DQ<1>
  VSS2  = GND
  DQS0_A_T  = M_F_CPU1_SA_DQS_DP<0>
  DQS0_A_C  = M_F_CPU1_SA_DQS_DN<0>
  VSS3  = GND
  DQ4_A  = M_F_CPU1_SA_DQ<4>
  VSS4  = GND
  DQ5_A  = M_F_CPU1_SA_DQ<5>
  VSS5  = GND
  DQ8_A  = M_F_CPU1_SA_DQ<8>
  VSS6  = GND
  DQ9_A  = M_F_CPU1_SA_DQ<9>
  VSS7  = GND
  DQS1_A_T  = M_F_CPU1_SA_DQS_DP<1>
  DQS1_A_C  = M_F_CPU1_SA_DQS_DN<1>
  VSS8  = GND
  DQ12_A  = M_F_CPU1_SA_DQ<12>
  VSS9  = GND
  DQ13_A  = M_F_CPU1_SA_DQ<13>
  VSS10  = GND
  DQ16_A  = M_F_CPU1_SA_DQ<16>
  VSS11  = GND
  DQ17_A  = M_F_CPU1_SA_DQ<17>
  VSS12  = GND
  DQS2_A_T  = M_F_CPU1_SA_DQS_DP<2>
  DQS2_A_C  = M_F_CPU1_SA_DQS_DN<2>
  VSS13  = GND
  DQ20_A  = M_F_CPU1_SA_DQ<20>
  VSS14  = GND
  DQ21_A  = M_F_CPU1_SA_DQ<21>
  VSS15  = GND
  DQ24_A  = M_F_CPU1_SA_DQ<24>
  VSS16  = GND
  DQ25_A  = M_F_CPU1_SA_DQ<25>
  VSS17  = GND
  DQS3_A_T  = M_F_CPU1_SA_DQS_DP<3>
  DQS3_A_C  = M_F_CPU1_SA_DQS_DN<3>
  VSS18  = GND
  DQ28_A  = M_F_CPU1_SA_DQ<28>
  VSS19  = GND
  DQ29_A  = M_F_CPU1_SA_DQ<29>
  VSS20  = GND
  CB0_A  = M_F_CPU1_SA_CB<0>
  VSS21  = GND
  CB1_A  = M_F_CPU1_SA_CB<1>
  VSS22  = GND
  DQS4_A_T  = M_F_CPU1_SA_DQS_DP<4>
  DQS4_A_C  = M_F_CPU1_SA_DQS_DN<4>
  VSS23  = GND
  CB4_A  = M_F_CPU1_SA_CB<4>
  VSS24  = GND
  CB5_A  = M_F_CPU1_SA_CB<5>
  VSS25  = GND
  ALERT_N  = M_F_CPU1_ALERT_N
  VSS26  = GND
  CS0_A_N  = M_F_CPU1_SA_CS_N<2>
  VSS27  = GND
  CA0_A  = M_F_CPU1_SA_CA<0>
  VSS28  = GND
  CA2_A  = M_F_CPU1_SA_CA<2>
  VSS29  = GND
  CA4_A  = M_F_CPU1_SA_CA<4>
  VSS30  = GND
  CA6_A  = M_F_CPU1_SA_CA<6>
  VSS31  = GND
  PAR_A  = M_F_CPU1_SA_PAR
  VSS32  = GND
  CA0_B  = M_F_CPU1_SB_CA<0>
  VSS33  = GND
  CA2_B  = M_F_CPU1_SB_CA<2>
  VSS34  = GND
  CA4_B  = M_F_CPU1_SB_CA<4>
  VSS35  = GND
  CA6_B  = M_F_CPU1_SB_CA<6>
  VSS36  = GND
  CS0_B_N  = M_F_CPU1_SB_CS_N<2>
  VSS37  = GND
  \lbd||rsp_a_n\  = M_F_CPU1_SA_RSP<1>
  \lbs||rsp_b_n\  = M_F_CPU1_SB_RSP<1>
  VSS38  = GND
  CB4_B  = M_F_CPU1_SB_CB<4>
  VSS39  = GND
  CB5_B  = M_F_CPU1_SB_CB<5>
  VSS40  = GND
  \dqs9_b_t||tdqs9_b_t||dbi4_b_n\  = M_F_CPU1_SB_DQS_DP<9>
  \dqs9_b_c||tdqs9_b_c\  = M_F_CPU1_SB_DQS_DN<9>
  VSS41  = GND
  CB0_B  = M_F_CPU1_SB_CB<0>
  VSS42  = GND
  CB1_B  = M_F_CPU1_SB_CB<1>
  VSS43  = GND
  DQ0_B  = M_F_CPU1_SB_DQ<0>
  VSS44  = GND
  DQ1_B  = M_F_CPU1_SB_DQ<1>
  VSS45  = GND
  DQS0_B_T  = M_F_CPU1_SB_DQS_DP<0>
  DQS0_B_C  = M_F_CPU1_SB_DQS_DN<0>
  VSS46  = GND
  DQ4_B  = M_F_CPU1_SB_DQ<4>
  VSS47  = GND
  DQ5_B  = M_F_CPU1_SB_DQ<5>
  VSS48  = GND
  DQ8_B  = M_F_CPU1_SB_DQ<8>
  VSS49  = GND
  DQ9_B  = M_F_CPU1_SB_DQ<9>
  VSS50  = GND
  DQS1_B_T  = M_F_CPU1_SB_DQS_DP<1>
  DQS1_B_C  = M_F_CPU1_SB_DQS_DN<1>
  VSS51  = GND
  DQ12_B  = M_F_CPU1_SB_DQ<12>
  VSS52  = GND
  DQ13_B  = M_F_CPU1_SB_DQ<13>
  VSS53  = GND
  DQ16_B  = M_F_CPU1_SB_DQ<16>
  VSS54  = GND
  DQ17_B  = M_F_CPU1_SB_DQ<17>
  VSS55  = GND
  DQS2_B_T  = M_F_CPU1_SB_DQS_DP<2>
  DQS2_B_C  = M_F_CPU1_SB_DQS_DN<2>
  VSS56  = GND
  DQ20_B  = M_F_CPU1_SB_DQ<20>
  VSS57  = GND
  DQ21_B  = M_F_CPU1_SB_DQ<21>
  VSS58  = GND
  DQ24_B  = M_F_CPU1_SB_DQ<24>
  VSS59  = GND
  DQ25_B  = M_F_CPU1_SB_DQ<25>
  VSS60  = GND
  DQS3_B_T  = M_F_CPU1_SB_DQS_DP<3>
  DQS3_B_C  = M_F_CPU1_SB_DQS_DN<3>
  VSS61  = GND
  DQ28_B  = M_F_CPU1_SB_DQ<28>
  VSS62  = GND
  DQ29_B  = M_F_CPU1_SB_DQ<29>
  VSS63  = GND
  RFU1  = TP_CHF_CPU1_DIMM2_FRU_1
  VIN_BULK1  = P12V_S3_AUX_CPU1_NVDIMM
  VIN_BULK2  = P12V_S3_AUX_CPU1_NVDIMM
  \pwr_good||fail_n\  = PWRGD_CHF_CPU1_DIMM2
  HSA  = PD_CHF_CPU1_DIMM2_SAA
  RFU2  = TP_CHF_CPU1_DIMM2_FRU_2
  RFU3  = TP_CHF_CPU1_DIMM2_FRU_3
  VSS64  = GND
  DQ2_A  = M_F_CPU1_SA_DQ<2>
  VSS65  = GND
  DQ3_A  = M_F_CPU1_SA_DQ<3>
  VSS66  = GND
  \dqs5_a_c||tdqs5_a_c||dqs5_a_t||tdqs5_a_t\  = M_F_CPU1_SA_DQS_DN<5>
  \dqs5_a_t||tdqs5_a_t\  = M_F_CPU1_SA_DQS_DP<5>
  VSS67  = GND
  DQ6_A  = M_F_CPU1_SA_DQ<6>
  VSS68  = GND
  DQ7_A  = M_F_CPU1_SA_DQ<7>
  VSS69  = GND
  DQ10_A  = M_F_CPU1_SA_DQ<10>
  VSS70  = GND
  DQ11_A  = M_F_CPU1_SA_DQ<11>
  VSS71  = GND
  \dqs6_a_c||tdqs6_a_c||dqs6_a_t||tdqs6_a_t\  = M_F_CPU1_SA_DQS_DN<6>
  \dqs6_a_t||tdqs6_a_t\  = M_F_CPU1_SA_DQS_DP<6>
  VSS72  = GND
  DQ14_A  = M_F_CPU1_SA_DQ<14>
  VSS73  = GND
  DQ15_A  = M_F_CPU1_SA_DQ<15>
  VSS74  = GND
  DQ18_A  = M_F_CPU1_SA_DQ<18>
  VSS75  = GND
  DQ19_A  = M_F_CPU1_SA_DQ<19>
  VSS76  = GND
  \dqs7_a_c||tdqs7_a_c\  = M_F_CPU1_SA_DQS_DN<7>
  \dqs7_a_t||tdqs7_a_t\  = M_F_CPU1_SA_DQS_DP<7>
  VSS77  = GND
  DQ22_A  = M_F_CPU1_SA_DQ<22>
  VSS78  = GND
  DQ23_A  = M_F_CPU1_SA_DQ<23>
  VSS79  = GND
  DQ26_A  = M_F_CPU1_SA_DQ<26>
  VSS80  = GND
  DQ27_A  = M_F_CPU1_SA_DQ<27>
  VSS81  = GND
  \dqs8_a_c||tdqs8_a_c\  = M_F_CPU1_SA_DQS_DN<8>
  \dqs8_a_t||tdqs8_a_t\  = M_F_CPU1_SA_DQS_DP<8>
  VSS82  = GND
  DQ30_A  = M_F_CPU1_SA_DQ<30>
  VSS83  = GND
  DQ31_A  = M_F_CPU1_SA_DQ<31>
  VSS84  = GND
  CB2_A  = M_F_CPU1_SA_CB<2>
  VSS85  = GND
  CB3_A  = M_F_CPU1_SA_CB<3>
  VSS86  = GND
  \dqs9_a_c||tdqs9_a_c\  = M_F_CPU1_SA_DQS_DN<9>
  \dqs9_a_t||tdqs9_a_t\  = M_F_CPU1_SA_DQS_DP<9>
  VSS87  = GND
  CB6_A  = M_F_CPU1_SA_CB<6>
  VSS88  = GND
  CB7_A  = M_F_CPU1_SA_CB<7>
  VSS89  = GND
  RESET_N  = RST_M_EF_CPU1_FPGA_N
  VSS90  = GND
  CS1_A_N  = M_F_CPU1_SA_CS_N<3>
  VSS91  = GND
  CA1_A  = M_F_CPU1_SA_CA<1>
  VSS92  = GND
  CA3_A  = M_F_CPU1_SA_CA<3>
  VSS93  = GND
  CA5_A  = M_F_CPU1_SA_CA<5>
  VSS94  = GND
  CK_T  = M_F_CPU1_CLK_DP<1>
  CK_C  = M_F_CPU1_CLK_DN<1>
  VSS95  = GND
  RFU4  = TP_CHF_CPU1_DIMM2_FRU_4
  CA1_B  = M_F_CPU1_SB_CA<1>
  VSS96  = GND
  CA3_B  = M_F_CPU1_SB_CA<3>
  VSS97  = GND
  CA5_B  = M_F_CPU1_SB_CA<5>
  VSS98  = GND
  PAR_B  = M_F_CPU1_SB_PAR
  VSS99  = GND
  CS1_B_N  = M_F_CPU1_SB_CS_N<3>
  VSS100  = GND
  RFU5  = TP_CHF_CPU1_DIMM2_FRU_5
  RFU6  = TP_CHF_CPU1_DIMM2_FRU_6
  VSS101  = GND
  CB6_B  = M_F_CPU1_SB_CB<6>
  VSS102  = GND
  CB7_B  = M_F_CPU1_SB_CB<7>
  VSS103  = GND
  DQS4_B_C  = M_F_CPU1_SB_DQS_DN<4>
  DQS4_B_T  = M_F_CPU1_SB_DQS_DP<4>
  VSS104  = GND
  CB2_B  = M_F_CPU1_SB_CB<2>
  VSS105  = GND
  CB3_B  = M_F_CPU1_SB_CB<3>
  VSS106  = GND
  DQ2_B  = M_F_CPU1_SB_DQ<2>
  VSS107  = GND
  DQ3_B  = M_F_CPU1_SB_DQ<3>
  VSS108  = GND
  \dqs5_b_c||tdqs5_b_c\  = M_F_CPU1_SB_DQS_DN<5>
  \dqs5_b_t||tdqs5_b_t\  = M_F_CPU1_SB_DQS_DP<5>
  VSS109  = GND
  DQ6_B  = M_F_CPU1_SB_DQ<6>
  VSS110  = GND
  DQ7_B  = M_F_CPU1_SB_DQ<7>
  VSS111  = GND
  DQ10_B  = M_F_CPU1_SB_DQ<10>
  VSS112  = GND
  DQ11_B  = M_F_CPU1_SB_DQ<11>
  VSS113  = GND
  \dqs6_b_c||tdqs6_b_c\  = M_F_CPU1_SB_DQS_DN<6>
  \dqs6_b_t||tdqs6_b_t\  = M_F_CPU1_SB_DQS_DP<6>
  VSS114  = GND
  DQ14_B  = M_F_CPU1_SB_DQ<14>
  VSS115  = GND
  DQ15_B  = M_F_CPU1_SB_DQ<15>
  VSS116  = GND
  DQ18_B  = M_F_CPU1_SB_DQ<18>
  VSS117  = GND
  DQ19_B  = M_F_CPU1_SB_DQ<19>
  VSS118  = GND
  \dqs7_b_c||tdqs7_b_c\  = M_F_CPU1_SB_DQS_DN<7>
  \dqs7_b_t||tdqs7_b_t\  = M_F_CPU1_SB_DQS_DP<7>
  VSS119  = GND
  DQ22_B  = M_F_CPU1_SB_DQ<22>
  VSS120  = GND
  DQ23_B  = M_F_CPU1_SB_DQ<23>
  VSS121  = GND
  DQ26_B  = M_F_CPU1_SB_DQ<26>
  VSS122  = GND
  DQ27_B  = M_F_CPU1_SB_DQ<27>
  VSS123  = GND
  \dqs8_b_c||tdqs8_b_c\  = M_F_CPU1_SB_DQS_DN<8>
  \dqs8_b_t||tdqs8_b_t\  = M_F_CPU1_SB_DQS_DP<8>
  VSS124  = GND
  DQ30_B  = M_F_CPU1_SB_DQ<30>
  VSS125  = GND
  DQ31_B  = M_F_CPU1_SB_DQ<31>
  VSS126  = GND
  G1  = GND
  G2  = GND
  G3  = GND

(kicad_pcb
	(version 20260206)
	(generator "pcbnew")
	(generator_version "10.0")
	(general
		(thickness 1.6)
		(legacy_teardrops no)
	)
	(paper "A4")
	(title_block
		(title "03242023_DA0F0TMBIJ0_F0T_Motherboard_J_brd_V01_OCP.brd")
		(comment 1 "Grand Teton / footprint 3431 of 6105 (J28), pads 1-45 of 291")
	)
	(layers
		(0 "F.Cu" signal "TOP")
		(4 "In1.Cu" signal "GND")
		(6 "In2.Cu" signal "IN1")
		(8 "In3.Cu" signal "GND1")
		(10 "In4.Cu" signal "IN2")
		(12 "In5.Cu" signal "GND2")
		(14 "In6.Cu" signal "IN3")
		(16 "In7.Cu" signal "GND3")
		(18 "In8.Cu" signal "VCC")
		(20 "In9.Cu" signal "VCC1")
		(22 "In10.Cu" signal "GND4")
		(24 "In11.Cu" signal "IN4")
		(26 "In12.Cu" signal "GND5")
		(28 "In13.Cu" signal "IN5")
		(30 "In14.Cu" signal "GND6")
		(32 "In15.Cu" signal "IN6")
		(34 "In16.Cu" signal "GND7")
		(2 "B.Cu" signal "BOTTOM")
		(9 "F.Adhes" user "F.Adhesive")
		(11 "B.Adhes" user "B.Adhesive")
		(13 "F.Paste" user "Package Geometry/Pastemask Top")
		(15 "B.Paste" user "Package Geometry/Pastemask Bottom")
		(5 "F.SilkS" user "Ref Des/Silkscreen Top")
		(7 "B.SilkS" user "Ref Des/Silkscreen Bottom")
		(1 "F.Mask" user "Board Geometry/Soldermask Top")
		(3 "B.Mask" user "Board Geometry/Soldermask Bottom")
		(17 "Dwgs.User" user "User.Drawings")
		(19 "Cmts.User" user "User.Comments")
		(21 "Eco1.User" user "User.Eco1")
		(23 "Eco2.User" user "User.Eco2")
		(25 "Edge.Cuts" user "Board Geometry/Outline")
		(27 "Margin" user)
		(31 "F.CrtYd" user "Package Geometry/Place Bound Top")
		(29 "B.CrtYd" user "Package Geometry/Place Bound Bottom")
		(35 "F.Fab" user "Ref Des/Assembly Top")
		(33 "B.Fab" user "Ref Des/Assembly Bottom")
	)
	(footprint ""
		(layer "F.Cu")
		(at 175.95088 -258.091686)
		(property "Reference" "J28"
			(at -0.26924 -81.680812 0)
			(unlocked yes)
			(layer "F.SilkS")
			(effects
				(font
					(size 0.7874 0.5842)
					(thickness 0.1524)
				)
				(justify left)
			)
		)
		(property "Value" ""
			(at 0 0 0)
			(layer "F.Fab")
			(effects
				(font
					(size 1.27 1.27)
				)
			)
		)
		(duplicate_pad_numbers_are_jumpers no)
		(pad "1" smd rect
			(at -2.050034 -63.324994 270)
			(size 0.519938 1.4986)
			(layers "F.Cu" "F.Mask" "F.Paste")
			(net "P12V_S3_AUX_CPU1_NVDIMM")
		)
		(pad "2" smd rect
			(at -2.050034 -62.47511 270)
			(size 0.519938 1.4986)
			(layers "F.Cu" "F.Mask" "F.Paste")
			(net "TP_CHF_CPU1_DIMM2_FRU_0")
		)
		(pad "3" smd rect
			(at -2.050034 -61.624972 270)
			(size 0.519938 1.4986)
			(layers "F.Cu" "F.Mask" "F.Paste")
			(net "P3V3_AUX")
		)
		(pad "4" smd rect
			(at -2.050034 -60.775088 270)
			(size 0.519938 1.4986)
			(layers "F.Cu" "F.Mask" "F.Paste")
			(net "I3C_SPD_DDREFGH_CPU1_LVC1_SCL_3")
		)
		(pad "5" smd rect
			(at -2.050034 -59.92495 270)
			(size 0.519938 1.4986)
			(layers "F.Cu" "F.Mask" "F.Paste")
			(net "I3C_SPD_DDREFGH_CPU1_LVC1_SDA")
		)
		(pad "6" smd rect
			(at -2.050034 -59.075066 270)
			(size 0.519938 1.4986)
			(layers "F.Cu" "F.Mask" "F.Paste")
			(net "GND")
		)
		(pad "7" smd rect
			(at -2.050034 -58.224928 270)
			(size 0.519938 1.4986)
			(layers "F.Cu" "F.Mask" "F.Paste")
			(net "M_F_CPU1_SA_DQ<0>")
		)
		(pad "8" smd rect
			(at -2.050034 -57.375044 270)
			(size 0.519938 1.4986)
			(layers "F.Cu" "F.Mask" "F.Paste")
			(net "GND")
		)
		(pad "9" smd rect
			(at -2.050034 -56.524906 270)
			(size 0.519938 1.4986)
			(layers "F.Cu" "F.Mask" "F.Paste")
			(net "M_F_CPU1_SA_DQ<1>")
		)
		(pad "10" smd rect
			(at -2.050034 -55.675022 270)
			(size 0.519938 1.4986)
			(layers "F.Cu" "F.Mask" "F.Paste")
			(net "GND")
		)
		(pad "11" smd rect
			(at -2.050034 -54.824884 270)
			(size 0.519938 1.4986)
			(layers "F.Cu" "F.Mask" "F.Paste")
			(net "M_F_CPU1_SA_DQS_DP<0>")
		)
		(pad "12" smd rect
			(at -2.050034 -53.975 270)
			(size 0.519938 1.4986)
			(layers "F.Cu" "F.Mask" "F.Paste")
			(net "M_F_CPU1_SA_DQS_DN<0>")
		)
		(pad "13" smd rect
			(at -2.050034 -53.125116 270)
			(size 0.519938 1.4986)
			(layers "F.Cu" "F.Mask" "F.Paste")
			(net "GND")
		)
		(pad "14" smd rect
			(at -2.050034 -52.274978 270)
			(size 0.519938 1.4986)
			(layers "F.Cu" "F.Mask" "F.Paste")
			(net "M_F_CPU1_SA_DQ<4>")
		)
		(pad "15" smd rect
			(at -2.050034 -51.425094 270)
			(size 0.519938 1.4986)
			(layers "F.Cu" "F.Mask" "F.Paste")
			(net "GND")
		)
		(pad "16" smd rect
			(at -2.050034 -50.574956 270)
			(size 0.519938 1.4986)
			(layers "F.Cu" "F.Mask" "F.Paste")
			(net "M_F_CPU1_SA_DQ<5>")
		)
		(pad "17" smd rect
			(at -2.050034 -49.725072 270)
			(size 0.519938 1.4986)
			(layers "F.Cu" "F.Mask" "F.Paste")
			(net "GND")
		)
		(pad "18" smd rect
			(at -2.050034 -48.874934 270)
			(size 0.519938 1.4986)
			(layers "F.Cu" "F.Mask" "F.Paste")
			(net "M_F_CPU1_SA_DQ<8>")
		)
		(pad "19" smd rect
			(at -2.050034 -48.02505 270)
			(size 0.519938 1.4986)
			(layers "F.Cu" "F.Mask" "F.Paste")
			(net "GND")
		)
		(pad "20" smd rect
			(at -2.050034 -47.174912 270)
			(size 0.519938 1.4986)
			(layers "F.Cu" "F.Mask" "F.Paste")
			(net "M_F_CPU1_SA_DQ<9>")
		)
		(pad "21" smd rect
			(at -2.050034 -46.325028 270)
			(size 0.519938 1.4986)
			(layers "F.Cu" "F.Mask" "F.Paste")
			(net "GND")
		)
		(pad "22" smd rect
			(at -2.050034 -45.47489 270)
			(size 0.519938 1.4986)
			(layers "F.Cu" "F.Mask" "F.Paste")
			(net "M_F_CPU1_SA_DQS_DP<1>")
		)
		(pad "23" smd rect
			(at -2.050034 -44.625006 270)
			(size 0.519938 1.4986)
			(layers "F.Cu" "F.Mask" "F.Paste")
			(net "M_F_CPU1_SA_DQS_DN<1>")
		)
		(pad "24" smd rect
			(at -2.050034 -43.775122 270)
			(size 0.519938 1.4986)
			(layers "F.Cu" "F.Mask" "F.Paste")
			(net "GND")
		)
		(pad "25" smd rect
			(at -2.050034 -42.924984 270)
			(size 0.519938 1.4986)
			(layers "F.Cu" "F.Mask" "F.Paste")
			(net "M_F_CPU1_SA_DQ<12>")
		)
		(pad "26" smd rect
			(at -2.050034 -42.0751 270)
			(size 0.519938 1.4986)
			(layers "F.Cu" "F.Mask" "F.Paste")
			(net "GND")
		)
		(pad "27" smd rect
			(at -2.050034 -41.224962 270)
			(size 0.519938 1.4986)
			(layers "F.Cu" "F.Mask" "F.Paste")
			(net "M_F_CPU1_SA_DQ<13>")
		)
		(pad "28" smd rect
			(at -2.050034 -40.375078 270)
			(size 0.519938 1.4986)
			(layers "F.Cu" "F.Mask" "F.Paste")
			(net "GND")
		)
		(pad "29" smd rect
			(at -2.050034 -39.52494 270)
			(size 0.519938 1.4986)
			(layers "F.Cu" "F.Mask" "F.Paste")
			(net "M_F_CPU1_SA_DQ<16>")
		)
		(pad "30" smd rect
			(at -2.050034 -38.675056 270)
			(size 0.519938 1.4986)
			(layers "F.Cu" "F.Mask" "F.Paste")
			(net "GND")
		)
		(pad "31" smd rect
			(at -2.050034 -37.824918 270)
			(size 0.519938 1.4986)
			(layers "F.Cu" "F.Mask" "F.Paste")
			(net "M_F_CPU1_SA_DQ<17>")
		)
		(pad "32" smd rect
			(at -2.050034 -36.975034 270)
			(size 0.519938 1.4986)
			(layers "F.Cu" "F.Mask" "F.Paste")
			(net "GND")
		)
		(pad "33" smd rect
			(at -2.050034 -36.124896 270)
			(size 0.519938 1.4986)
			(layers "F.Cu" "F.Mask" "F.Paste")
			(net "M_F_CPU1_SA_DQS_DP<2>")
		)
		(pad "34" smd rect
			(at -2.050034 -35.275012 270)
			(size 0.519938 1.4986)
			(layers "F.Cu" "F.Mask" "F.Paste")
			(net "M_F_CPU1_SA_DQS_DN<2>")
		)
		(pad "35" smd rect
			(at -2.050034 -34.425128 270)
			(size 0.519938 1.4986)
			(layers "F.Cu" "F.Mask" "F.Paste")
			(net "GND")
		)
		(pad "36" smd rect
			(at -2.050034 -33.57499 270)
			(size 0.519938 1.4986)
			(layers "F.Cu" "F.Mask" "F.Paste")
			(net "M_F_CPU1_SA_DQ<20>")
		)
		(pad "37" smd rect
			(at -2.050034 -32.725106 270)
			(size 0.519938 1.4986)
			(layers "F.Cu" "F.Mask" "F.Paste")
			(net "GND")
		)
		(pad "38" smd rect
			(at -2.050034 -31.874968 270)
			(size 0.519938 1.4986)
			(layers "F.Cu" "F.Mask" "F.Paste")
			(net "M_F_CPU1_SA_DQ<21>")
		)
		(pad "39" smd rect
			(at -2.050034 -31.025084 270)
			(size 0.519938 1.4986)
			(layers "F.Cu" "F.Mask" "F.Paste")
			(net "GND")
		)
		(pad "40" smd rect
			(at -2.050034 -30.174946 270)
			(size 0.519938 1.4986)
			(layers "F.Cu" "F.Mask" "F.Paste")
			(net "M_F_CPU1_SA_DQ<24>")
		)
		(pad "41" smd rect
			(at -2.050034 -29.325062 270)
			(size 0.519938 1.4986)
			(layers "F.Cu" "F.Mask" "F.Paste")
			(net "GND")
		)
		(pad "42" smd rect
			(at -2.050034 -28.474924 270)
			(size 0.519938 1.4986)
			(layers "F.Cu" "F.Mask" "F.Paste")
			(net "M_F_CPU1_SA_DQ<25>")
		)
		(pad "43" smd rect
			(at -2.050034 -27.62504 270)
			(size 0.519938 1.4986)
			(layers "F.Cu" "F.Mask" "F.Paste")
			(net "GND")
		)
		(pad "44" smd rect
			(at -2.050034 -26.774902 270)
			(size 0.519938 1.4986)
			(layers "F.Cu" "F.Mask" "F.Paste")
			(net "M_F_CPU1_SA_DQS_DP<3>")
		)
		(pad "45" smd rect
			(at -2.050034 -25.925018 270)
			(size 0.519938 1.4986)
			(layers "F.Cu" "F.Mask" "F.Paste")
			(net "M_F_CPU1_SA_DQS_DN<3>")
		)
	)
)
